(kicad_pcb
	(version 20241229)
	(generator "pcbnew")
	(generator_version "9.0")
	(general
		(thickness 1.711)
		(legacy_teardrops no)
	)
	(paper "A4")
	(title_block
		(title "Antmicro Baseboard for Jetson AGX Thor")
		(date "2026-02-18")
		(rev "1.1.0")
		(company "Antmicro Ltd")
		(comment 1 "www.antmicro.com")
		(comment 9 "footprints 68-72 of 1170")
	)
	(layers
		(0 "F.Cu" signal)
		(4 "In1.Cu" signal)
		(6 "In2.Cu" signal)
		(8 "In3.Cu" signal)
		(10 "In4.Cu" jumper)
		(12 "In5.Cu" signal)
		(14 "In6.Cu" signal)
		(16 "In7.Cu" signal)
		(18 "In8.Cu" signal)
		(2 "B.Cu" signal)
		(9 "F.Adhes" user "F.Adhesive")
		(11 "B.Adhes" user "B.Adhesive")
		(13 "F.Paste" user)
		(15 "B.Paste" user)
		(5 "F.SilkS" user "F.Silkscreen")
		(7 "B.SilkS" user "B.Silkscreen")
		(1 "F.Mask" user)
		(3 "B.Mask" user)
		(17 "Dwgs.User" user "User.Drawings")
		(19 "Cmts.User" user "User.Comments")
		(21 "Eco1.User" user "User.Eco1")
		(23 "Eco2.User" user "User.Eco2")
		(25 "Edge.Cuts" user)
		(27 "Margin" user)
		(31 "F.CrtYd" user "F.Courtyard")
		(29 "B.CrtYd" user "B.Courtyard")
		(35 "F.Fab" user)
		(33 "B.Fab" user)
	)
	(footprint "antmicro-footprints:R_0402_1005Metric"
		(layer "F.Cu")
		(at 213.8 120.1 -90)
		(descr "Resistor SMD 0402")
		(tags "resistor SMD 0402")
		(property "Reference" "R91"
			(at -3.055 0.38 90)
			(layer "F.SilkS")
			(effects
				(font
					(size 0.7 0.7)
					(thickness 0.15)
				)
				(justify right top)
			)
		)
		(property "Value" "R_200k_0402"
			(at -1.011843 1.772046 90)
			(layer "F.Fab")
			(effects
				(font
					(size 0.7 0.7)
					(thickness 0.15)
				)
				(justify right top)
			)
		)
		(property "Datasheet" "https://www.bourns.com/docs/product-datasheets/cr.pdf"
			(at 0 0 90)
			(layer "F.Fab")
			(hide yes)
			(effects
				(font
					(size 1.27 1.27)
					(thickness 0.15)
				)
			)
		)
		(property "Description" "SMD Chip Resistor, 200 kohm, ± 1%, 62.5 mW, 0402 [1005 Metric], Thick Film, General Purpose"
			(at 0 0 90)
			(layer "F.Fab")
			(hide yes)
			(effects
				(font
					(size 1.27 1.27)
					(thickness 0.15)
				)
			)
		)
		(property "MPN" "CR0402-FX-2003GLF"
			(at 0 0 270)
			(unlocked yes)
			(layer "F.Fab")
			(hide yes)
			(effects
				(font
					(size 1 1)
					(thickness 0.15)
				)
			)
		)
		(property "Manufacturer" "Bourns"
			(at 0 0 270)
			(unlocked yes)
			(layer "F.Fab")
			(hide yes)
			(effects
				(font
					(size 1 1)
					(thickness 0.15)
				)
			)
		)
		(property "License" "Apache-2.0"
			(at 0 0 270)
			(unlocked yes)
			(layer "F.Fab")
			(hide yes)
			(effects
				(font
					(size 1 1)
					(thickness 0.15)
				)
			)
		)
		(property "Author" "Antmicro"
			(at 0 0 270)
			(unlocked yes)
			(layer "F.Fab")
			(hide yes)
			(effects
				(font
					(size 1 1)
					(thickness 0.15)
				)
			)
		)
		(property "Val" "200k"
			(at 0 0 270)
			(unlocked yes)
			(layer "F.Fab")
			(hide yes)
			(effects
				(font
					(size 1 1)
					(thickness 0.15)
				)
			)
		)
		(property "Tolerance" "1%"
			(at 0 0 270)
			(unlocked yes)
			(layer "F.Fab")
			(hide yes)
			(effects
				(font
					(size 1 1)
					(thickness 0.15)
				)
			)
		)
		(sheetname "/USB Hub/")
		(sheetfile "usb_hub.kicad_sch")
		(attr smd)
		(fp_poly
			(pts
				(xy -0.925 -0.47) (xy 0.925 -0.47) (xy 0.925 0.47) (xy -0.925 0.47)
			)
			(stroke
				(width 0.05)
				(type default)
			)
			(fill no)
			(layer "F.CrtYd")
		)
		(fp_poly
			(pts
				(xy -0.5 -0.25) (xy 0.5 -0.25) (xy 0.5 0.25) (xy -0.5 0.25)
			)
			(stroke
				(width 0.15)
				(type solid)
			)
			(fill no)
			(layer "F.Fab")
		)
		(fp_text user "Author: Antmicro"
			(at -0.95 4.169 90)
			(layer "F.Fab")
			(effects
				(font
					(size 0.7 0.7)
					(thickness 0.15)
				)
				(justify right top)
			)
		)
		(fp_text user "License: Apache-2.0"
			(at -0.949999 5.169 90)
			(layer "F.Fab")
			(effects
				(font
					(size 0.7 0.7)
					(thickness 0.15)
				)
				(justify right top)
			)
		)
		(fp_text user "${REFERENCE}"
			(at -0.95 3.168 90)
			(layer "F.Fab")
			(effects
				(font
					(size 0.7 0.7)
					(thickness 0.15)
				)
				(justify right top)
			)
		)
		(pad "1" smd roundrect
			(at -0.48 0 270)
			(size 0.59 0.64)
			(layers "F.Cu" "F.Mask" "F.Paste")
			(roundrect_rratio 0.25)
			(net 1 "GND")
			(pintype "passive")
		)
		(pad "2" smd roundrect
			(at 0.48 0 270)
			(size 0.59 0.64)
			(layers "F.Cu" "F.Mask" "F.Paste")
			(roundrect_rratio 0.25)
			(net 931 "/USB Hub/CFG_STRAP3")
			(pintype "passive")
		)
	)
	(footprint "antmicro-footprints:C_0402_1005Metric"
		(layer "F.Cu")
		(at 219.124 105.2 180)
		(descr "Capacitor SMD 0402")
		(tags "capacitor SMD 0402")
		(property "Reference" "C107"
			(at -1.18 -0.76 0)
			(layer "F.SilkS")
			(effects
				(font
					(size 0.7 0.7)
					(thickness 0.15)
				)
				(justify right top)
			)
		)
		(property "Value" "C_100n_0402"
			(at -1.022927 2.155213 0)
			(layer "F.Fab")
			(effects
				(font
					(size 0.7 0.7)
					(thickness 0.15)
				)
				(justify right top)
			)
		)
		(property "Datasheet" "https://www.murata.com/products/productdetail?partno=GRM155R61H104KE14%23"
			(at 0 0 0)
			(layer "F.Fab")
			(hide yes)
			(effects
				(font
					(size 1.27 1.27)
					(thickness 0.15)
				)
			)
		)
		(property "Description" "SMD Multilayer Ceramic Capacitor, 0.1 µF, 50 V, 0402 [1005 Metric], ± 10%, X5R, GRM Series"
			(at 0 0 0)
			(layer "F.Fab")
			(hide yes)
			(effects
				(font
					(size 1.27 1.27)
					(thickness 0.15)
				)
			)
		)
		(property "Manufacturer" "Murata"
			(at 0 0 180)
			(unlocked yes)
			(layer "F.Fab")
			(hide yes)
			(effects
				(font
					(size 1 1)
					(thickness 0.15)
				)
			)
		)
		(property "MPN" "GRM155R61H104KE14D"
			(at 0 0 180)
			(unlocked yes)
			(layer "F.Fab")
			(hide yes)
			(effects
				(font
					(size 1 1)
					(thickness 0.15)
				)
			)
		)
		(property "Val" "100n"
			(at 0 0 180)
			(unlocked yes)
			(layer "F.Fab")
			(hide yes)
			(effects
				(font
					(size 1 1)
					(thickness 0.15)
				)
			)
		)
		(property "License" "Apache-2.0"
			(at 0 0 180)
			(unlocked yes)
			(layer "F.Fab")
			(hide yes)
			(effects
				(font
					(size 1 1)
					(thickness 0.15)
				)
			)
		)
		(property "Author" "Antmicro"
			(at 0 0 180)
			(unlocked yes)
			(layer "F.Fab")
			(hide yes)
			(effects
				(font
					(size 1 1)
					(thickness 0.15)
				)
			)
		)
		(property "Voltage" "50V"
			(at 0 0 180)
			(unlocked yes)
			(layer "F.Fab")
			(hide yes)
			(effects
				(font
					(size 1 1)
					(thickness 0.15)
				)
			)
		)
		(property "Dielectric" "X5R"
			(at 0 0 180)
			(unlocked yes)
			(layer "F.Fab")
			(hide yes)
			(effects
				(font
					(size 1 1)
					(thickness 0.15)
				)
			)
		)
		(sheetname "/Recovery USB/")
		(sheetfile "recovery_usb.kicad_sch")
		(attr smd)
		(fp_rect
			(start -0.925 -0.47)
			(end 0.925 0.47)
			(stroke
				(width 0.05)
				(type default)
			)
			(fill no)
			(layer "F.CrtYd")
		)
		(fp_line
			(start 0.504 0.248)
			(end -0.494 0.248)
			(stroke
				(width 0.15)
				(type solid)
			)
			(layer "F.Fab")
		)
		(fp_line
			(start 0.504 -0.25)
			(end 0.504 0.248)
			(stroke
				(width 0.15)
				(type solid)
			)
			(layer "F.Fab")
		)
		(fp_line
			(start -0.494 0.248)
			(end -0.494 -0.25)
			(stroke
				(width 0.15)
				(type solid)
			)
			(layer "F.Fab")
		)
		(fp_line
			(start -0.494 -0.25)
			(end 0.504 -0.25)
			(stroke
				(width 0.15)
				(type solid)
			)
			(layer "F.Fab")
		)
		(fp_text user "Author: Antmicro"
			(at -0.939 3.399 0)
			(layer "F.Fab")
			(effects
				(font
					(size 0.7 0.7)
					(thickness 0.15)
				)
				(justify right top)
			)
		)
		(fp_text user "License: Apache-2.0"
			(at -0.939 5.799 0)
			(layer "F.Fab")
			(effects
				(font
					(size 0.7 0.7)
					(thickness 0.15)
				)
				(justify right top)
			)
		)
		(fp_text user "${REFERENCE}"
			(at -0.939 4.599 0)
			(layer "F.Fab")
			(effects
				(font
					(size 0.7 0.7)
					(thickness 0.15)
				)
				(justify right top)
			)
		)
		(pad "1" smd roundrect
			(at -0.48 0 180)
			(size 0.59 0.64)
			(layers "F.Cu" "F.Mask" "F.Paste")
			(roundrect_rratio 0.25)
			(net 215 "/Recovery USB/USBC2_CONN_TX1_N")
			(pintype "passive")
		)
		(pad "2" smd roundrect
			(at 0.48 0 180)
			(size 0.59 0.64)
			(layers "F.Cu" "F.Mask" "F.Paste")
			(roundrect_rratio 0.25)
			(net 234 "/Recovery USB/USBC2_TX1_N")
			(pintype "passive")
		)
	)
	(footprint "antmicro-footprints:C_0603_1608Metric_EIA"
		(layer "F.Cu")
		(at 192.47 126.88)
		(descr "Capacitor SMD 0603, IPC-7351 Density Level A")
		(tags "Capacitor 0603")
		(property "Reference" "C310"
			(at -1.47 8.32 0)
			(layer "F.SilkS")
			(effects
				(font
					(size 0.7 0.7)
					(thickness 0.15)
				)
				(justify left bottom)
			)
		)
		(property "Value" "C_22u_16V_0603"
			(at -1.42757 1.770288 0)
			(layer "F.Fab")
			(effects
				(font
					(size 0.7 0.7)
					(thickness 0.15)
				)
				(justify left bottom)
			)
		)
		(property "Datasheet" "https://product.samsungsem.com/mlcc/CL10A226MO7JZN.do"
			(at 0 0 0)
			(layer "F.Fab")
			(hide yes)
			(effects
				(font
					(size 1.27 1.27)
					(thickness 0.15)
				)
			)
		)
		(property "Description" "SMD Multilayer Ceramic Capacitor"
			(at 0 0 0)
			(layer "F.Fab")
			(hide yes)
			(effects
				(font
					(size 1.27 1.27)
					(thickness 0.15)
				)
			)
		)
		(property "MPN" "CL10A226MO7JZNC"
			(at 0 0 0)
			(unlocked yes)
			(layer "F.Fab")
			(hide yes)
			(effects
				(font
					(size 1 1)
					(thickness 0.15)
				)
			)
		)
		(property "Manufacturer" "Samsung Electro-Mechanics"
			(at 0 0 0)
			(unlocked yes)
			(layer "F.Fab")
			(hide yes)
			(effects
				(font
					(size 1 1)
					(thickness 0.15)
				)
			)
		)
		(property "License" "Apache-2.0"
			(at 0 0 0)
			(unlocked yes)
			(layer "F.Fab")
			(hide yes)
			(effects
				(font
					(size 1 1)
					(thickness 0.15)
				)
			)
		)
		(property "Author" "Antmicro"
			(at 0 0 0)
			(unlocked yes)
			(layer "F.Fab")
			(hide yes)
			(effects
				(font
					(size 1 1)
					(thickness 0.15)
				)
			)
		)
		(property "Val" "22u"
			(at 0 0 0)
			(unlocked yes)
			(layer "F.Fab")
			(hide yes)
			(effects
				(font
					(size 1 1)
					(thickness 0.15)
				)
			)
		)
		(property "Voltage" "16V"
			(at 0 0 0)
			(unlocked yes)
			(layer "F.Fab")
			(hide yes)
			(effects
				(font
					(size 1 1)
					(thickness 0.15)
				)
			)
		)
		(property "Dielectric" ""
			(at 0 0 0)
			(unlocked yes)
			(layer "F.Fab")
			(hide yes)
			(effects
				(font
					(size 1 1)
					(thickness 0.15)
				)
			)
		)
		(component_classes
			(class "DCDC_1V15")
		)
		(sheetname "/DCDC/")
		(sheetfile "dcdc.kicad_sch")
		(attr smd)
		(fp_line
			(start -0.15 -0.55)
			(end 0.15 -0.55)
			(stroke
				(width 0.15)
				(type solid)
			)
			(layer "F.SilkS")
		)
		(fp_line
			(start -0.15 0.55)
			(end 0.15 0.55)
			(stroke
				(width 0.15)
				(type solid)
			)
			(layer "F.SilkS")
		)
		(fp_rect
			(start -1.25 -0.65)
			(end 1.25 0.65)
			(stroke
				(width 0.05)
				(type solid)
			)
			(fill no)
			(layer "F.CrtYd")
		)
		(fp_rect
			(start -0.8 -0.45)
			(end 0.8 0.45)
			(stroke
				(width 0.15)
				(type solid)
			)
			(fill no)
			(layer "F.Fab")
		)
		(fp_text user "Author: Antmicro"
			(at -1.682 4.894 0)
			(layer "F.Fab")
			(effects
				(font
					(size 0.7 0.7)
					(thickness 0.15)
				)
				(justify left bottom)
			)
		)
		(fp_text user "License: Apache-2.0"
			(at -1.682 5.895 0)
			(layer "F.Fab")
			(effects
				(font
					(size 0.7 0.7)
					(thickness 0.15)
				)
				(justify left bottom)
			)
		)
		(fp_text user "${REFERENCE}"
			(at -1.682 3.895 0)
			(layer "F.Fab")
			(effects
				(font
					(size 0.7 0.7)
					(thickness 0.15)
				)
				(justify left bottom)
			)
		)
		(pad "1" smd roundrect
			(at -0.7 0)
			(size 0.8 1.1)
			(layers "F.Cu" "F.Mask" "F.Paste")
			(roundrect_rratio 0.2)
			(net 1 "GND")
			(pintype "passive")
		)
		(pad "2" smd roundrect
			(at 0.7 0)
			(size 0.8 1.1)
			(layers "F.Cu" "F.Mask" "F.Paste")
			(roundrect_rratio 0.2)
			(net 280 "/DCDC/1V15_OUT")
			(pintype "passive")
		)
	)
	(footprint "antmicro-footprints:C_0805_2012Metric"
		(layer "F.Cu")
		(at 147.5 91)
		(descr "Capacitor SMD 0805")
		(tags "capacitor SMD 0805")
		(property "Reference" "C26"
			(at -2.3 -0.3 180)
			(layer "F.SilkS")
			(effects
				(font
					(size 0.7 0.7)
					(thickness 0.15)
				)
				(justify right top)
			)
		)
		(property "Value" "C_22u_25V_0805"
			(at -2.055717 1.963153 180)
			(layer "F.Fab")
			(effects
				(font
					(size 0.7 0.7)
					(thickness 0.15)
				)
				(justify right top)
			)
		)
		(property "Datasheet" "https://product.samsungsem.com/mlcc/CL21A226MAYNNN.do"
			(at 0 0 180)
			(layer "F.Fab")
			(hide yes)
			(effects
				(font
					(size 1.27 1.27)
					(thickness 0.15)
				)
			)
		)
		(property "Description" "SMT Multilayer Ceramic Capacitor, 22uF, +/-20%, 25V, X5R, 0805 [2012 Metric]"
			(at 0 0 180)
			(layer "F.Fab")
			(hide yes)
			(effects
				(font
					(size 1.27 1.27)
					(thickness 0.15)
				)
			)
		)
		(property "MPN" "CL21A226MAYNNNE"
			(at 0 0 0)
			(unlocked yes)
			(layer "F.Fab")
			(hide yes)
			(effects
				(font
					(size 1 1)
					(thickness 0.15)
				)
			)
		)
		(property "Manufacturer" "Samsung Electro-Mechanics"
			(at 0 0 0)
			(unlocked yes)
			(layer "F.Fab")
			(hide yes)
			(effects
				(font
					(size 1 1)
					(thickness 0.15)
				)
			)
		)
		(property "License" "Apache-2.0"
			(at 0 0 0)
			(unlocked yes)
			(layer "F.Fab")
			(hide yes)
			(effects
				(font
					(size 1 1)
					(thickness 0.15)
				)
			)
		)
		(property "Author" "Antmicro"
			(at 0 0 0)
			(unlocked yes)
			(layer "F.Fab")
			(hide yes)
			(effects
				(font
					(size 1 1)
					(thickness 0.15)
				)
			)
		)
		(property "Val" "22u"
			(at 0 0 0)
			(unlocked yes)
			(layer "F.Fab")
			(hide yes)
			(effects
				(font
					(size 1 1)
					(thickness 0.15)
				)
			)
		)
		(property "Voltage" "25V"
			(at 0 0 0)
			(unlocked yes)
			(layer "F.Fab")
			(hide yes)
			(effects
				(font
					(size 1 1)
					(thickness 0.15)
				)
			)
		)
		(property "Dielectric" "X5R"
			(at 0 0 0)
			(unlocked yes)
			(layer "F.Fab")
			(hide yes)
			(effects
				(font
					(size 1 1)
					(thickness 0.15)
				)
			)
		)
		(property "Public" "False"
			(at 0 0 0)
			(unlocked yes)
			(layer "F.Fab")
			(hide yes)
			(effects
				(font
					(size 1 1)
					(thickness 0.15)
				)
			)
		)
		(sheetname "/SoM_Power/")
		(sheetfile "som_power.kicad_sch")
		(attr smd)
		(fp_line
			(start -0.3 -0.7)
			(end 0.3 -0.7)
			(stroke
				(width 0.15)
				(type solid)
			)
			(layer "F.SilkS")
		)
		(fp_line
			(start -0.3 0.7)
			(end 0.3 0.7)
			(stroke
				(width 0.15)
				(type solid)
			)
			(layer "F.SilkS")
		)
		(fp_poly
			(pts
				(xy 1.95 -0.9) (xy -1.95 -0.9) (xy -1.95 0.9) (xy 1.95 0.9)
			)
			(stroke
				(width 0.05)
				(type default)
			)
			(fill no)
			(layer "F.CrtYd")
		)
		(fp_poly
			(pts
				(xy -0.95 -0.675001) (xy 0.95 -0.675001) (xy 0.95 0.675001) (xy -0.95 0.675001)
			)
			(stroke
				(width 0.15)
				(type solid)
			)
			(fill no)
			(layer "F.Fab")
		)
		(fp_text user "${REFERENCE}"
			(at -1.899999 3.947 180)
			(layer "F.Fab")
			(effects
				(font
					(size 0.7 0.7)
					(thickness 0.15)
				)
				(justify right top)
			)
		)
		(fp_text user "License: Apache-2.0"
			(at -1.9 4.947 180)
			(layer "F.Fab")
			(effects
				(font
					(size 0.7 0.7)
					(thickness 0.15)
				)
				(justify right top)
			)
		)
		(fp_text user "Author: Antmicro"
			(at -1.9 5.947 180)
			(layer "F.Fab")
			(effects
				(font
					(size 0.7 0.7)
					(thickness 0.15)
				)
				(justify right top)
			)
		)
		(pad "1" smd roundrect
			(at -1.099999 0)
			(size 1.2 1.3)
			(layers "F.Cu" "F.Mask" "F.Paste")
			(roundrect_rratio 0.25)
			(net 1 "GND")
			(pintype "passive")
		)
		(pad "2" smd roundrect
			(at 1.099999 0)
			(size 1.2 1.3)
			(layers "F.Cu" "F.Mask" "F.Paste")
			(roundrect_rratio 0.25)
			(net 12 "SYS_VIN_HV")
			(pintype "passive")
		)
	)
	(footprint "antmicro-footprints:C_0402_1005Metric"
		(layer "F.Cu")
		(at 212.8 120.1 -90)
		(descr "Capacitor SMD 0402")
		(tags "capacitor SMD 0402")
		(property "Reference" "C90"
			(at -3 0.3 90)
			(layer "F.SilkS")
			(effects
				(font
					(size 0.7 0.7)
					(thickness 0.15)
				)
				(justify right top)
			)
		)
		(property "Value" "C_100n_0402"
			(at -1.022927 2.155213 90)
			(layer "F.Fab")
			(effects
				(font
					(size 0.7 0.7)
					(thickness 0.15)
				)
				(justify right top)
			)
		)
		(property "Datasheet" "https://www.murata.com/products/productdetail?partno=GRM155R61H104KE14%23"
			(at 0 0 90)
			(layer "F.Fab")
			(hide yes)
			(effects
				(font
					(size 1.27 1.27)
					(thickness 0.15)
				)
			)
		)
		(property "Description" "SMD Multilayer Ceramic Capacitor, 0.1 µF, 50 V, 0402 [1005 Metric], ± 10%, X5R, GRM Series"
			(at 0 0 90)
			(layer "F.Fab")
			(hide yes)
			(effects
				(font
					(size 1.27 1.27)
					(thickness 0.15)
				)
			)
		)
		(property "MPN" "GRM155R61H104KE14D"
			(at 0 0 270)
			(unlocked yes)
			(layer "F.Fab")
			(hide yes)
			(effects
				(font
					(size 1 1)
					(thickness 0.15)
				)
			)
		)
		(property "Val" "100n"
			(at 0 0 270)
			(unlocked yes)
			(layer "F.Fab")
			(hide yes)
			(effects
				(font
					(size 1 1)
					(thickness 0.15)
				)
			)
		)
		(property "Voltage" "50V"
			(at 0 0 270)
			(unlocked yes)
			(layer "F.Fab")
			(hide yes)
			(effects
				(font
					(size 1 1)
					(thickness 0.15)
				)
			)
		)
		(property "Dielectric" "X5R"
			(at 0 0 270)
			(unlocked yes)
			(layer "F.Fab")
			(hide yes)
			(effects
				(font
					(size 1 1)
					(thickness 0.15)
				)
			)
		)
		(property "Manufacturer" "Murata"
			(at 0 0 270)
			(unlocked yes)
			(layer "F.Fab")
			(hide yes)
			(effects
				(font
					(size 1 1)
					(thickness 0.15)
				)
			)
		)
		(property "License" "Apache-2.0"
			(at 0 0 270)
			(unlocked yes)
			(layer "F.Fab")
			(hide yes)
			(effects
				(font
					(size 1 1)
					(thickness 0.15)
				)
			)
		)
		(property "Author" "Antmicro"
			(at 0 0 270)
			(unlocked yes)
			(layer "F.Fab")
			(hide yes)
			(effects
				(font
					(size 1 1)
					(thickness 0.15)
				)
			)
		)
		(sheetname "/USB Hub/")
		(sheetfile "usb_hub.kicad_sch")
		(attr smd)
		(fp_poly
			(pts
				(xy -0.925 -0.47) (xy -0.925 0.47) (xy 0.925 0.47) (xy 0.925 -0.47)
			)
			(stroke
				(width 0.05)
				(type default)
			)
			(fill no)
			(layer "F.CrtYd")
		)
		(fp_line
			(start -0.494 0.248)
			(end -0.494 -0.25)
			(stroke
				(width 0.15)
				(type solid)
			)
			(layer "F.Fab")
		)
		(fp_line
			(start 0.504 0.248)
			(end -0.494 0.248)
			(stroke
				(width 0.15)
				(type solid)
			)
			(layer "F.Fab")
		)
		(fp_line
			(start -0.494 -0.25)
			(end 0.504 -0.25)
			(stroke
				(width 0.15)
				(type solid)
			)
			(layer "F.Fab")
		)
		(fp_line
			(start 0.504 -0.25)
			(end 0.504 0.248)
			(stroke
				(width 0.15)
				(type solid)
			)
			(layer "F.Fab")
		)
		(fp_text user "Author: Antmicro"
			(at -0.939 3.399 90)
			(layer "F.Fab")
			(effects
				(font
					(size 0.7 0.7)
					(thickness 0.15)
				)
				(justify right top)
			)
		)
		(fp_text user "${REFERENCE}"
			(at -0.939 4.599 90)
			(layer "F.Fab")
			(effects
				(font
					(size 0.7 0.7)
					(thickness 0.15)
				)
				(justify right top)
			)
		)
		(fp_text user "License: Apache-2.0"
			(at -0.939 5.799 90)
			(layer "F.Fab")
			(effects
				(font
					(size 0.7 0.7)
					(thickness 0.15)
				)
				(justify right top)
			)
		)
		(pad "1" smd roundrect
			(at -0.48 0 270)
			(size 0.59 0.64)
			(layers "F.Cu" "F.Mask" "F.Paste")
			(roundrect_rratio 0.25)
			(net 1 "GND")
			(pintype "passive")
		)
		(pad "2" smd roundrect
			(at 0.48 0 270)
			(size 0.59 0.64)
			(layers "F.Cu" "F.Mask" "F.Paste")
			(roundrect_rratio 0.25)
			(net 282 "+1V15")
			(pintype "passive")
		)
	)
)
